# Wiwynn_Honey Badger_PTB_4L_Stackup_20150121.xlsx — Wiwynn (pcb-stackup)
|  |  |  |  |  |  |  |  |  |  |  | Single Ended Type(mil) |  |  |  |
|  |  |  |  |  |  |  |  |  |  | Imp | 50 |  |  |  |
|  |  |  |  |  |  |  |  |  |  | Variation | Inner /Outer ±5Ω |  |  |  |
|  |  |  |  |  |  |  |  |  |  | Bus | MISC |  |  |  |
|  |  |  |  |  |  |  |  |  |  | Type | SE |  |  |  |
| Layer |  |  |  | Thickness |  | Glass style | Er |  | Df(1G) | Layers | All |  |  |  |
|  |  |  | Cu oz | Wiwynn | Vender |  | Wiwynn | Vender |  |  | Wiwynn |  | Vender |  |
|  | Mask |  |  | 0.5 |  |  | 3.8 |  |  |  | Width | Imp | Width | Imp |
| Top | Signal |  | 0.5 oz + plating | 1.7 |  |  |  |  |  | S1 | 5.5 |  |  |  |
|  | Prepreg |  |  | 3.5 |  |  | 4 |  |  |  |  |  |  |  |
| L2 | PWR | GND | 1 oz | 2.6 |  |  |  |  |  | P2 | Reference layer |  | Reference layer |  |
|  | Core |  |  | 47 |  |  | 4.5 |  |  |  |  |  |  |  |
| L3 | PWR | GND | 1 oz | 2.6 |  |  |  |  |  | P3 | Reference layer |  | Reference layer |  |
|  | Prepreg |  |  | 3.5 |  |  | 4 |  |  |  |  |  |  |  |
| Bottom | Signal |  | 0.5 oz + plating | 1.7 |  |  |  |  |  | S4 | 5.5 |  |  |  |
|  | Mask |  |  | 0.5 |  |  | 3.8 |  |  |  |  |  |  |  |
| Thickness requirement: 1.62±10% mm |  |  | mil | 63.6 |  | +/-10% |  |  |  |  |  |  |  |  |
|  |  |  | mm | 1.6154432308864619 |  |  |  |  |  |  |  |  |  |  |
